#ISCELL
  mstr_misc dns *
  *
#ISCELL
  pure_quanta quanta_title_block_c *
  *
#ISCELL
  logical_power universal_gnd *
  page254_i1
#ISCELL
  logical_power universal_gnd *
  page254_i10
#CELL
  pure_quanta q_cap *
  page254_i11
#CELL
  pure_quanta q_cap *
  page254_i12
#CELL
  pure_quanta isl99390frztr5935 *
  page254_i13
#CELL
  pure_quanta q_res *
  page254_i14
#ISCELL
  logical_power vcc15 *
  page254_i15
#ISCELL
  logical_power universal_gnd *
  page254_i16
#CELL
  pure_quanta q_cap *
  page254_i17
#ISCELL
  standard offpage *
  page254_i18
#ISCELL
  standard offpage *
  page254_i19
#CELL
  pure_quanta q_res *
  page254_i2
#CELL
  pure_quanta isl99390frztr5935 *
  page254_i20
#ISCELL
  logical_power universal_gnd *
  page254_i21
#ISCELL
  standard offpage *
  page254_i22
#ISCELL
  standard offpage *
  page254_i23
#ISCELL
  logical_power universal_gnd *
  page254_i24
#CELL
  pure_quanta q_cap *
  page254_i25
#CELL
  pure_quanta q_cap *
  page254_i26
#CELL
  pure_quanta q_res *
  page254_i27
#ISCELL
  logical_power vcc15 *
  page254_i28
#ISCELL
  logical_power universal_gnd *
  page254_i29
#ISCELL
  logical_power universal_gnd *
  page254_i3
#CELL
  pure_quanta q_cap *
  page254_i30
#ISCELL
  logical_power universal_gnd *
  page254_i31
#ISCELL
  standard offpage *
  page254_i32
#CELL
  pure_quanta q_inductor4p_14 *
  page254_i33
#CELL
  pure_quanta q_cap *
  page254_i34
#CELL
  pure_quanta q_cap *
  page254_i35
#CELL
  pure_quanta q_res *
  page254_i36
#ISCELL
  logical_power universal_gnd *
  page254_i37
#CELL
  pure_quanta q_cap *
  page254_i38
#CELL
  pure_quanta q_cap *
  page254_i39
#CELL
  pure_quanta q_res *
  page254_i4
#CELL
  pure_quanta q_cap *
  page254_i40
#CELL
  pure_quanta q_res *
  page254_i41
#ISCELL
  standard offpage *
  page254_i42
#CELL
  pure_quanta q_cap *
  page254_i43
#ISCELL
  logical_power universal_gnd *
  page254_i44
#ISCELL
  logical_power vcc15 *
  page254_i45
#CELL
  pure_quanta q_res *
  page254_i46
#ISCELL
  standard offpage *
  page254_i47
#CELL
  pure_quanta q_cap *
  page254_i48
#CELL
  pure_quanta q_res *
  page254_i49
#ISCELL
  logical_power universal_gnd *
  page254_i5
#CELL
  pure_quanta q_inductor4p_14 *
  page254_i50
#CELL
  pure_quanta q_cap *
  page254_i51
#CELL
  pure_quanta q_cap *
  page254_i52
#CELL
  pure_quanta q_cap *
  page254_i53
#CELL
  pure_quanta q_cap *
  page254_i54
#ISCELL
  logical_power universal_gnd *
  page254_i55
#CELL
  pure_quanta q_cap *
  page254_i56
#ISCELL
  logical_power vcc15 *
  page254_i57
#ISCELL
  standard offpage *
  page254_i58
#CELL
  pure_quanta q_cap *
  page254_i59
#ISCELL
  standard offpage *
  page254_i6
#CELL
  pure_quanta q_cap *
  page254_i60
#CELL
  pure_quanta q_cap *
  page254_i61
#ISCELL
  logical_power universal_gnd *
  page254_i62
#ISCELL
  logical_power vcc15 *
  page254_i63
#ISCELL
  logical_power universal_gnd *
  page254_i64
#CELL
  pure_quanta q_cap *
  page254_i65
#ISCELL
  logical_power vcc15 *
  page254_i66
#ISCELL
  standard offpage *
  page254_i7
#ISCELL
  standard offpage *
  page254_i8
#ISCELL
  standard offpage *
  page254_i9
